# T6G (Grand Teton) — schematic netlist excerpt (pin names and nets, part order shuffled) for the footprints in the layout excerpt that follows; sources: Cadence DE-HDL packaged netlist, KiCad conversion of 04192023_DAF0TMB3IC0_F0TG_MB_C_brd_V02_OCP.brd

R310  Q_RES  1K 1% CHIP  pkg 0402LF  page 105 : A = PWRGD_CHH_CPU1_DIMM ; B = PWRGD_CHGL_CPU1
C656  Q_CAP  22UF 4V 20% X6S  pkg C0402  page 290 : A = P0V9_CPU0_RT1_2A ; B = GND

(kicad_pcb
	(version 20260206)
	(generator "pcbnew")
	(generator_version "10.0")
	(general
		(thickness 1.6)
		(legacy_teardrops no)
	)
	(paper "A4")
	(title_block
		(title "04192023_DAF0TMB3IC0_F0TG_MB_C_brd_V02_OCP.brd")
		(comment 1 "Grand Teton / footprints 5497-5498 of 8354")
	)
	(layers
		(0 "F.Cu" signal "TOP")
		(4 "In1.Cu" signal "GND")
		(6 "In2.Cu" signal "IN1")
		(8 "In3.Cu" signal "GND1")
		(10 "In4.Cu" signal "IN2")
		(12 "In5.Cu" signal "GND2")
		(14 "In6.Cu" signal "IN3")
		(16 "In7.Cu" signal "GND3")
		(18 "In8.Cu" signal "VCC")
		(20 "In9.Cu" signal "VCC1")
		(22 "In10.Cu" signal "GND4")
		(24 "In11.Cu" signal "IN4")
		(26 "In12.Cu" signal "GND5")
		(28 "In13.Cu" signal "IN5")
		(30 "In14.Cu" signal "GND6")
		(32 "In15.Cu" signal "IN6")
		(34 "In16.Cu" signal "GND7")
		(2 "B.Cu" signal "BOTTOM")
		(9 "F.Adhes" user "F.Adhesive")
		(11 "B.Adhes" user "B.Adhesive")
		(13 "F.Paste" user "Package Geometry/Pastemask Top")
		(15 "B.Paste" user "Package Geometry/Pastemask Bottom")
		(5 "F.SilkS" user "Ref Des/Silkscreen Top")
		(7 "B.SilkS" user "Ref Des/Silkscreen Bottom")
		(1 "F.Mask" user "Board Geometry/Soldermask Top")
		(3 "B.Mask" user "Board Geometry/Soldermask Bottom")
		(17 "Dwgs.User" user "User.Drawings")
		(19 "Cmts.User" user "User.Comments")
		(21 "Eco1.User" user "User.Eco1")
		(23 "Eco2.User" user "User.Eco2")
		(25 "Edge.Cuts" user "Board Geometry/Outline")
		(27 "Margin" user)
		(31 "F.CrtYd" user "Package Geometry/Place Bound Top")
		(29 "B.CrtYd" user "Package Geometry/Place Bound Bottom")
		(35 "F.Fab" user "Ref Des/Assembly Top")
		(33 "B.Fab" user "Ref Des/Assembly Bottom")
	)
	(footprint ""
		(layer "B.Cu")
		(at 351.518728 -398.942052 90)
		(property "Reference" "C656"
			(at 0 0 90)
			(layer "B.SilkS")
			(hide yes)
			(effects
				(font
					(size 1.27 1.27)
				)
				(justify mirror)
			)
		)
		(property "Value" ""
			(at 0 0 90)
			(layer "B.Fab")
			(effects
				(font
					(size 1.27 1.27)
				)
				(justify mirror)
			)
		)
		(duplicate_pad_numbers_are_jumpers no)
		(fp_line
			(start 0.7874 -0.4064)
			(end -0.7874 -0.4064)
			(stroke
				(width 0.1524)
				(type default)
			)
			(layer "B.SilkS")
		)
		(fp_line
			(start -0.7874 -0.4064)
			(end -0.7874 0.4064)
			(stroke
				(width 0.1524)
				(type default)
			)
			(layer "B.SilkS")
		)
		(fp_line
			(start 0.7874 0.4064)
			(end 0.7874 -0.4064)
			(stroke
				(width 0.1524)
				(type default)
			)
			(layer "B.SilkS")
		)
		(fp_line
			(start -0.7874 0.4064)
			(end 0.7874 0.4064)
			(stroke
				(width 0.1524)
				(type default)
			)
			(layer "B.SilkS")
		)
		(fp_line
			(start 0.67945 -0.305054)
			(end 0.12065 -0.305054)
			(stroke
				(width 0.1)
				(type default)
			)
			(layer "B.Fab")
		)
		(fp_line
			(start 0.12065 -0.305054)
			(end 0.12065 -0.2794)
			(stroke
				(width 0.1)
				(type default)
			)
			(layer "B.Fab")
		)
		(fp_line
			(start -0.12065 -0.3048)
			(end -0.67945 -0.3048)
			(stroke
				(width 0.1)
				(type default)
			)
			(layer "B.Fab")
		)
		(fp_line
			(start -0.67945 -0.3048)
			(end -0.67945 0.3048)
			(stroke
				(width 0.1)
				(type default)
			)
			(layer "B.Fab")
		)
		(fp_line
			(start 0.12065 -0.2794)
			(end -0.12065 -0.2794)
			(stroke
				(width 0.1)
				(type default)
			)
			(layer "B.Fab")
		)
		(fp_line
			(start -0.12065 -0.2794)
			(end -0.12065 -0.3048)
			(stroke
				(width 0.1)
				(type default)
			)
			(layer "B.Fab")
		)
		(fp_line
			(start 0.12065 0.2794)
			(end 0.12065 0.3048)
			(stroke
				(width 0.1)
				(type default)
			)
			(layer "B.Fab")
		)
		(fp_line
			(start -0.120396 0.2794)
			(end 0.12065 0.2794)
			(stroke
				(width 0.1)
				(type default)
			)
			(layer "B.Fab")
		)
		(fp_line
			(start 0.67945 0.3048)
			(end 0.67945 -0.305054)
			(stroke
				(width 0.1)
				(type default)
			)
			(layer "B.Fab")
		)
		(fp_line
			(start 0.12065 0.3048)
			(end 0.67945 0.3048)
			(stroke
				(width 0.1)
				(type default)
			)
			(layer "B.Fab")
		)
		(fp_line
			(start -0.120396 0.3048)
			(end -0.120396 0.2794)
			(stroke
				(width 0.1)
				(type default)
			)
			(layer "B.Fab")
		)
		(fp_line
			(start -0.67945 0.3048)
			(end -0.120396 0.3048)
			(stroke
				(width 0.1)
				(type default)
			)
			(layer "B.Fab")
		)
		(pad "1" smd circle
			(at 0.40005 0 270)
			(size 0 0)
			(layers "B.Cu" "B.Mask" "B.Paste")
			(net "P0V9_CPU0_RT1_2A")
		)
		(pad "2" smd circle
			(at -0.40005 0 270)
			(size 0 0)
			(layers "B.Cu" "B.Mask" "B.Paste")
			(net "GND")
		)
	)
	(footprint ""
		(layer "B.Cu")
		(at 171.82846 -190.948564 180)
		(property "Reference" "R310"
			(at 0 0 0)
			(layer "B.SilkS")
			(hide yes)
			(effects
				(font
					(size 1.27 1.27)
				)
				(justify mirror)
			)
		)
		(property "Value" ""
			(at 0 0 0)
			(layer "B.Fab")
			(effects
				(font
					(size 1.27 1.27)
				)
				(justify mirror)
			)
		)
		(duplicate_pad_numbers_are_jumpers no)
		(fp_line
			(start 0.7874 0.4064)
			(end 0.7874 -0.4064)
			(stroke
				(width 0.1524)
				(type default)
			)
			(layer "B.SilkS")
		)
		(fp_line
			(start 0.7874 -0.4064)
			(end -0.7874 -0.4064)
			(stroke
				(width 0.1524)
				(type default)
			)
			(layer "B.SilkS")
		)
		(fp_line
			(start -0.7874 0.4064)
			(end 0.7874 0.4064)
			(stroke
				(width 0.1524)
				(type default)
			)
			(layer "B.SilkS")
		)
		(fp_line
			(start -0.7874 -0.4064)
			(end -0.7874 0.4064)
			(stroke
				(width 0.1524)
				(type default)
			)
			(layer "B.SilkS")
		)
		(fp_line
			(start 0.67945 0.3048)
			(end 0.67945 -0.305054)
			(stroke
				(width 0.1)
				(type default)
			)
			(layer "B.Fab")
		)
		(fp_line
			(start 0.67945 -0.305054)
			(end 0.12065 -0.305054)
			(stroke
				(width 0.1)
				(type default)
			)
			(layer "B.Fab")
		)
		(fp_line
			(start 0.12065 0.3048)
			(end 0.67945 0.3048)
			(stroke
				(width 0.1)
				(type default)
			)
			(layer "B.Fab")
		)
		(fp_line
			(start 0.12065 0.2794)
			(end 0.12065 0.3048)
			(stroke
				(width 0.1)
				(type default)
			)
			(layer "B.Fab")
		)
		(fp_line
			(start 0.12065 -0.2794)
			(end -0.12065 -0.2794)
			(stroke
				(width 0.1)
				(type default)
			)
			(layer "B.Fab")
		)
		(fp_line
			(start 0.12065 -0.305054)
			(end 0.12065 -0.2794)
			(stroke
				(width 0.1)
				(type default)
			)
			(layer "B.Fab")
		)
		(fp_line
			(start -0.120396 0.3048)
			(end -0.120396 0.2794)
			(stroke
				(width 0.1)
				(type default)
			)
			(layer "B.Fab")
		)
		(fp_line
			(start -0.120396 0.2794)
			(end 0.12065 0.2794)
			(stroke
				(width 0.1)
				(type default)
			)
			(layer "B.Fab")
		)
		(fp_line
			(start -0.12065 -0.2794)
			(end -0.12065 -0.3048)
			(stroke
				(width 0.1)
				(type default)
			)
			(layer "B.Fab")
		)
		(fp_line
			(start -0.12065 -0.3048)
			(end -0.67945 -0.3048)
			(stroke
				(width 0.1)
				(type default)
			)
			(layer "B.Fab")
		)
		(fp_line
			(start -0.67945 0.3048)
			(end -0.120396 0.3048)
			(stroke
				(width 0.1)
				(type default)
			)
			(layer "B.Fab")
		)
		(fp_line
			(start -0.67945 -0.3048)
			(end -0.67945 0.3048)
			(stroke
				(width 0.1)
				(type default)
			)
			(layer "B.Fab")
		)
		(pad "1" smd circle
			(at 0.40005 0)
			(size 0 0)
			(layers "B.Cu" "B.Mask" "B.Paste")
			(net "PWRGD_CHH_CPU1_DIMM")
		)
		(pad "2" smd circle
			(at -0.40005 0)
			(size 0 0)
			(layers "B.Cu" "B.Mask" "B.Paste")
			(net "PWRGD_CHGL_CPU1")
		)
	)
)
